# T6G (Grand Teton) — schematic netlist excerpt (pin names and nets, part order shuffled) for the footprints in the layout excerpt that follows; sources: Cadence DE-HDL packaged netlist, KiCad conversion of 04192023_DAF0TMB3IC0_F0TG_MB_C_brd_V02_OCP.brd

J99  SCONN288_DDR506112002KQ  IO  pkg DDR288S_1-1VXC  page 108
  VIN_BULK0  = P12V_MEM_CPU1
  RFU0  = NC
  VIN_MGMT  = P3V3_AUX
  HSCL  = I3C_SPD_DDRK_CPU1_SCL
  HSDA  = I3C_SPD_DDRK_CPU1_SDA
  VSS0  = GND
  DQ0_A  = M_K_CPU1_SA_DQ<0>
  VSS1  = GND
  DQ1_A  = M_K_CPU1_SA_DQ<1>
  VSS2  = GND
  DQS0_A_T  = M_K_CPU1_SA_DQS_DP<0>
  DQS0_A_C  = M_K_CPU1_SA_DQS_DN<0>
  VSS3  = GND
  DQ4_A  = M_K_CPU1_SA_DQ<4>
  VSS4  = GND
  DQ5_A  = M_K_CPU1_SA_DQ<5>
  VSS5  = GND
  DQ8_A  = M_K_CPU1_SA_DQ<8>
  VSS6  = GND
  DQ9_A  = M_K_CPU1_SA_DQ<9>
  VSS7  = GND
  DQS1_A_T  = M_K_CPU1_SA_DQS_DP<1>
  DQS1_A_C  = M_K_CPU1_SA_DQS_DN<1>
  VSS8  = GND
  DQ12_A  = M_K_CPU1_SA_DQ<12>
  VSS9  = GND
  DQ13_A  = M_K_CPU1_SA_DQ<13>
  VSS10  = GND
  DQ16_A  = M_K_CPU1_SA_DQ<16>
  VSS11  = GND
  DQ17_A  = M_K_CPU1_SA_DQ<17>
  VSS12  = GND
  DQS2_A_T  = M_K_CPU1_SA_DQS_DP<2>
  DQS2_A_C  = M_K_CPU1_SA_DQS_DN<2>
  VSS13  = GND
  DQ20_A  = M_K_CPU1_SA_DQ<20>
  VSS14  = GND
  DQ21_A  = M_K_CPU1_SA_DQ<21>
  VSS15  = GND
  DQ24_A  = M_K_CPU1_SA_DQ<24>
  VSS16  = GND
  DQ25_A  = M_K_CPU1_SA_DQ<25>
  VSS17  = GND
  DQS3_A_T  = M_K_CPU1_SA_DQS_DP<3>
  DQS3_A_C  = M_K_CPU1_SA_DQS_DN<3>
  VSS18  = GND
  DQ28_A  = M_K_CPU1_SA_DQ<28>
  VSS19  = GND
  DQ29_A  = M_K_CPU1_SA_DQ<29>
  VSS20  = GND
  CB0_A  = M_K_CPU1_SA_CB<0>
  VSS21  = GND
  CB1_A  = M_K_CPU1_SA_CB<1>
  VSS22  = GND
  DQS4_A_T  = M_K_CPU1_SA_DQS_DP<4>
  DQS4_A_C  = M_K_CPU1_SA_DQS_DN<4>
  VSS23  = GND
  CB4_A  = M_K_CPU1_SA_CB<4>
  VSS24  = GND
  CB5_A  = M_K_CPU1_SA_CB<5>
  VSS25  = GND
  ALERT_N  = M_K_CPU1_ALERT_N
  VSS26  = GND
  CS0_A_N  = M_K_CPU1_SA_CS_N<0>
  VSS27  = GND
  CA0_A  = M_K_CPU1_SA_CA<0>
  VSS28  = GND
  CA2_A  = M_K_CPU1_SA_CA<2>
  VSS29  = GND
  CA4_A  = M_K_CPU1_SA_CA<4>
  VSS30  = GND
  CA6_A  = M_K_CPU1_SA_CA<6>
  VSS31  = GND
  PAR_A  = M_K_CPU1_SA_PAR
  VSS32  = GND
  CA0_B  = M_K_CPU1_SB_CA<0>
  VSS33  = GND
  CA2_B  = M_K_CPU1_SB_CA<2>
  VSS34  = GND
  CA4_B  = M_K_CPU1_SB_CA<4>
  VSS35  = GND
  CA6_B  = M_K_CPU1_SB_CA<6>
  VSS36  = GND
  CS0_B_N  = M_K_CPU1_SB_CS_N<0>
  VSS37  = GND
  \lbd||rsp_a_n\  = M_K_CPU1_SA_RSP<0>
  \lbs||rsp_b_n\  = M_K_CPU1_SB_RSP<0>
  VSS38  = GND
  CB4_B  = M_K_CPU1_SB_CB<4>
  VSS39  = GND
  CB5_B  = M_K_CPU1_SB_CB<5>
  VSS40  = GND
  \dqs9_b_t||tdqs9_b_t||dbi4_b_n\  = M_K_CPU1_SB_DQS_DP<9>
  \dqs9_b_c||tdqs9_b_c\  = M_K_CPU1_SB_DQS_DN<9>
  VSS41  = GND
  CB0_B  = M_K_CPU1_SB_CB<0>
  VSS42  = GND
  CB1_B  = M_K_CPU1_SB_CB<1>
  VSS43  = GND
  DQ0_B  = M_K_CPU1_SB_DQ<0>
  VSS44  = GND
  DQ1_B  = M_K_CPU1_SB_DQ<1>
  VSS45  = GND
  DQS0_B_T  = M_K_CPU1_SB_DQS_DP<0>
  DQS0_B_C  = M_K_CPU1_SB_DQS_DN<0>
  VSS46  = GND
  DQ4_B  = M_K_CPU1_SB_DQ<4>
  VSS47  = GND
  DQ5_B  = M_K_CPU1_SB_DQ<5>
  VSS48  = GND
  DQ8_B  = M_K_CPU1_SB_DQ<8>
  VSS49  = GND
  DQ9_B  = M_K_CPU1_SB_DQ<9>
  VSS50  = GND
  DQS1_B_T  = M_K_CPU1_SB_DQS_DP<1>
  DQS1_B_C  = M_K_CPU1_SB_DQS_DN<1>
  VSS51  = GND
  DQ12_B  = M_K_CPU1_SB_DQ<12>
  VSS52  = GND
  DQ13_B  = M_K_CPU1_SB_DQ<13>
  VSS53  = GND
  DQ16_B  = M_K_CPU1_SB_DQ<16>
  VSS54  = GND
  DQ17_B  = M_K_CPU1_SB_DQ<17>
  VSS55  = GND
  DQS2_B_T  = M_K_CPU1_SB_DQS_DP<2>
  DQS2_B_C  = M_K_CPU1_SB_DQS_DN<2>
  VSS56  = GND
  DQ20_B  = M_K_CPU1_SB_DQ<20>
  VSS57  = GND
  DQ21_B  = M_K_CPU1_SB_DQ<21>
  VSS58  = GND
  DQ24_B  = M_K_CPU1_SB_DQ<24>
  VSS59  = GND
  DQ25_B  = M_K_CPU1_SB_DQ<25>
  VSS60  = GND
  DQS3_B_T  = M_K_CPU1_SB_DQS_DP<3>
  DQS3_B_C  = M_K_CPU1_SB_DQS_DN<3>
  VSS61  = GND
  DQ28_B  = M_K_CPU1_SB_DQ<28>
  VSS62  = GND
  DQ29_B  = M_K_CPU1_SB_DQ<29>
  VSS63  = GND
  RFU1  = NC
  VIN_BULK1  = P12V_MEM_CPU1
  VIN_BULK2  = P12V_MEM_CPU1
  \pwr_good||fail_n\  = PWRGD_CHK_CPU1_DIMM
  HAS  = PD_CHK_CPU1_DIMM_SAA
  RFU2  = NC
  RFU3  = NC
  VSS64  = GND
  DQ2_A  = M_K_CPU1_SA_DQ<2>
  VSS65  = GND
  DQ3_A  = M_K_CPU1_SA_DQ<3>
  VSS66  = GND
  \dqs5_a_c||tdqs5_a_c||dqs5_a_t||tdqs5_a_t\  = M_K_CPU1_SA_DQS_DN<5>
  \dqs5_a_t||tdqs5_a_t\  = M_K_CPU1_SA_DQS_DP<5>
  VSS67  = GND
  DQ6_A  = M_K_CPU1_SA_DQ<6>
  VSS68  = GND
  DQ7_A  = M_K_CPU1_SA_DQ<7>
  VSS69  = GND
  DQ10_A  = M_K_CPU1_SA_DQ<10>
  VSS70  = GND
  DQ11_A  = M_K_CPU1_SA_DQ<11>
  VSS71  = GND
  \dqs6_a_c||tdqs6_a_c||dqs6_a_t||tdqs6_a_t\  = M_K_CPU1_SA_DQS_DN<6>
  \dqs6_a_t||tdqs6_a_t\  = M_K_CPU1_SA_DQS_DP<6>
  VSS72  = GND
  DQ14_A  = M_K_CPU1_SA_DQ<14>
  VSS73  = GND
  DQ15_A  = M_K_CPU1_SA_DQ<15>
  VSS74  = GND
  DQ18_A  = M_K_CPU1_SA_DQ<18>
  VSS75  = GND
  DQ19_A  = M_K_CPU1_SA_DQ<19>
  VSS76  = GND
  \dqs7_a_c||tdqs7_a_c\  = M_K_CPU1_SA_DQS_DN<7>
  \dqs7_a_t||tdqs7_a_t\  = M_K_CPU1_SA_DQS_DP<7>
  VSS77  = GND
  DQ22_A  = M_K_CPU1_SA_DQ<22>
  VSS78  = GND
  DQ23_A  = M_K_CPU1_SA_DQ<23>
  VSS79  = GND
  DQ26_A  = M_K_CPU1_SA_DQ<26>
  VSS80  = GND
  DQ27_A  = M_K_CPU1_SA_DQ<27>
  VSS81  = GND
  \dqs8_a_c||tdqs8_a_c\  = M_K_CPU1_SA_DQS_DN<8>
  \dqs8_a_t||tdqs8_a_t\  = M_K_CPU1_SA_DQS_DP<8>
  VSS82  = GND
  DQ30_A  = M_K_CPU1_SA_DQ<30>
  VSS83  = GND
  DQ31_A  = M_K_CPU1_SA_DQ<31>
  VSS84  = GND
  CB2_A  = M_K_CPU1_SA_CB<2>
  VSS85  = GND
  CB3_A  = M_K_CPU1_SA_CB<3>
  VSS86  = GND
  \dqs9_a_c||tdqs9_a_c\  = M_K_CPU1_SA_DQS_DN<9>
  \dqs9_a_t||tdqs9_a_t\  = M_K_CPU1_SA_DQS_DP<9>
  VSS87  = GND
  CB6_A  = M_K_CPU1_SA_CB<6>
  VSS88  = GND
  CB7_A  = M_K_CPU1_SA_CB<7>
  VSS89  = GND
  RESET_N  = M_K_CPU1_RESET_N
  VSS90  = GND
  CS1_A_N  = M_K_CPU1_SA_CS_N<1>
  VSS91  = GND
  CA1_A  = M_K_CPU1_SA_CA<1>
  VSS92  = GND
  CA3_A  = M_K_CPU1_SA_CA<3>
  VSS93  = GND
  CA5_A  = M_K_CPU1_SA_CA<5>
  VSS94  = GND
  CK_T  = M_K_CPU1_CLK_DP<0>
  CK_C  = M_K_CPU1_CLK_DN<0>
  VSS95  = GND
  RFU4  = NC
  CA1_B  = M_K_CPU1_SB_CA<1>
  VSS96  = GND
  CA3_B  = M_K_CPU1_SB_CA<3>
  VSS97  = GND
  CA5_B  = M_K_CPU1_SB_CA<5>
  VSS98  = GND
  PAR_B  = M_K_CPU1_SB_PAR
  VSS99  = GND
  CS1_B_N  = M_K_CPU1_SB_CS_N<1>
  VSS100  = GND
  RFU5  = NC
  RFU6  = NC
  VSS101  = GND
  CB6_B  = M_K_CPU1_SB_CB<6>
  VSS102  = GND
  CB7_B  = M_K_CPU1_SB_CB<7>
  VSS103  = GND
  DQS4_B_C  = M_K_CPU1_SB_DQS_DN<4>
  DQS4_B_T  = M_K_CPU1_SB_DQS_DP<4>
  VSS104  = GND
  CB2_B  = M_K_CPU1_SB_CB<2>
  VSS105  = GND
  CB3_B  = M_K_CPU1_SB_CB<3>
  VSS106  = GND
  DQ2_B  = M_K_CPU1_SB_DQ<2>
  VSS107  = GND
  DQ3_B  = M_K_CPU1_SB_DQ<3>
  VSS108  = GND
  \dqs5_b_c||tdqs5_b_c\  = M_K_CPU1_SB_DQS_DN<5>
  \dqs5_b_t||tdqs5_b_t\  = M_K_CPU1_SB_DQS_DP<5>
  VSS109  = GND
  DQ6_B  = M_K_CPU1_SB_DQ<6>
  VSS110  = GND
  DQ7_B  = M_K_CPU1_SB_DQ<7>
  VSS111  = GND
  DQ10_B  = M_K_CPU1_SB_DQ<10>
  VSS112  = GND
  DQ11_B  = M_K_CPU1_SB_DQ<11>
  VSS113  = GND
  \dqs6_b_c||tdqs6_b_c\  = M_K_CPU1_SB_DQS_DN<6>
  \dqs6_b_t||tdqs6_b_t\  = M_K_CPU1_SB_DQS_DP<6>
  VSS114  = GND
  DQ14_B  = M_K_CPU1_SB_DQ<14>
  VSS115  = GND
  DQ15_B  = M_K_CPU1_SB_DQ<15>
  VSS116  = GND
  DQ18_B  = M_K_CPU1_SB_DQ<18>
  VSS117  = GND
  DQ19_B  = M_K_CPU1_SB_DQ<19>
  VSS118  = GND
  \dqs7_b_c||tdqs7_b_c\  = M_K_CPU1_SB_DQS_DN<7>
  \dqs7_b_t||tdqs7_b_t\  = M_K_CPU1_SB_DQS_DP<7>
  VSS119  = GND
  DQ22_B  = M_K_CPU1_SB_DQ<22>
  VSS120  = GND
  DQ23_B  = M_K_CPU1_SB_DQ<23>
  VSS121  = GND
  DQ26_B  = M_K_CPU1_SB_DQ<26>
  VSS122  = GND
  DQ27_B  = M_K_CPU1_SB_DQ<27>
  VSS123  = GND
  \dqs8_b_c||tdqs8_b_c\  = M_K_CPU1_SB_DQS_DN<8>
  \dqs8_b_t||tdqs8_b_t\  = M_K_CPU1_SB_DQS_DP<8>
  VSS124  = GND
  DQ30_B  = M_K_CPU1_SB_DQ<30>
  VSS125  = GND
  DQ31_B  = M_K_CPU1_SB_DQ<31>
  VSS126  = GND
  G1  = GND
  G2  = GND
  G3  = GND

(kicad_pcb
	(version 20260206)
	(generator "pcbnew")
	(generator_version "10.0")
	(general
		(thickness 1.6)
		(legacy_teardrops no)
	)
	(paper "A4")
	(title_block
		(title "04192023_DAF0TMB3IC0_F0TG_MB_C_brd_V02_OCP.brd")
		(comment 1 "Grand Teton / footprint 4555 of 8354 (J99), pads 93-138 of 291")
	)
	(layers
		(0 "F.Cu" signal "TOP")
		(4 "In1.Cu" signal "GND")
		(6 "In2.Cu" signal "IN1")
		(8 "In3.Cu" signal "GND1")
		(10 "In4.Cu" signal "IN2")
		(12 "In5.Cu" signal "GND2")
		(14 "In6.Cu" signal "IN3")
		(16 "In7.Cu" signal "GND3")
		(18 "In8.Cu" signal "VCC")
		(20 "In9.Cu" signal "VCC1")
		(22 "In10.Cu" signal "GND4")
		(24 "In11.Cu" signal "IN4")
		(26 "In12.Cu" signal "GND5")
		(28 "In13.Cu" signal "IN5")
		(30 "In14.Cu" signal "GND6")
		(32 "In15.Cu" signal "IN6")
		(34 "In16.Cu" signal "GND7")
		(2 "B.Cu" signal "BOTTOM")
		(9 "F.Adhes" user "F.Adhesive")
		(11 "B.Adhes" user "B.Adhesive")
		(13 "F.Paste" user "Package Geometry/Pastemask Top")
		(15 "B.Paste" user "Package Geometry/Pastemask Bottom")
		(5 "F.SilkS" user "Ref Des/Silkscreen Top")
		(7 "B.SilkS" user "Ref Des/Silkscreen Bottom")
		(1 "F.Mask" user "Board Geometry/Soldermask Top")
		(3 "B.Mask" user "Board Geometry/Soldermask Bottom")
		(17 "Dwgs.User" user "User.Drawings")
		(19 "Cmts.User" user "User.Comments")
		(21 "Eco1.User" user "User.Eco1")
		(23 "Eco2.User" user "User.Eco2")
		(25 "Edge.Cuts" user "Board Geometry/Outline")
		(27 "Margin" user)
		(31 "F.CrtYd" user "Package Geometry/Place Bound Top")
		(29 "B.CrtYd" user "Package Geometry/Place Bound Bottom")
		(35 "F.Fab" user "Ref Des/Assembly Top")
		(33 "B.Fab" user "Ref Des/Assembly Bottom")
	)
	(footprint ""
		(layer "F.Cu")
		(at 196.654166 -255.560322 180)
		(property "Reference" "J99"
			(at -0.4318 -81.730088 0)
			(unlocked yes)
			(layer "F.SilkS")
			(effects
				(font
					(size 0.7874 0.5842)
					(thickness 0.1524)
				)
			)
		)
		(property "Value" ""
			(at 0 0 180)
			(layer "F.Fab")
			(effects
				(font
					(size 1.27 1.27)
				)
			)
		)
		(duplicate_pad_numbers_are_jumpers no)
		(pad "93" smd rect
			(at -2.050034 19.975068 90)
			(size 0.519938 1.4986)
			(layers "F.Cu" "F.Mask" "F.Paste")
			(net "M_K_CPU1_SB_DQS_DP<9>")
		)
		(pad "94" smd rect
			(at -2.050034 20.824952 90)
			(size 0.519938 1.4986)
			(layers "F.Cu" "F.Mask" "F.Paste")
			(net "M_K_CPU1_SB_DQS_DN<9>")
		)
		(pad "95" smd rect
			(at -2.050034 21.67509 90)
			(size 0.519938 1.4986)
			(layers "F.Cu" "F.Mask" "F.Paste")
			(net "GND")
		)
		(pad "96" smd rect
			(at -2.050034 22.524974 90)
			(size 0.519938 1.4986)
			(layers "F.Cu" "F.Mask" "F.Paste")
			(net "M_K_CPU1_SB_CB<0>")
		)
		(pad "97" smd rect
			(at -2.050034 23.375112 90)
			(size 0.519938 1.4986)
			(layers "F.Cu" "F.Mask" "F.Paste")
			(net "GND")
		)
		(pad "98" smd rect
			(at -2.050034 24.224996 90)
			(size 0.519938 1.4986)
			(layers "F.Cu" "F.Mask" "F.Paste")
			(net "M_K_CPU1_SB_CB<1>")
		)
		(pad "99" smd rect
			(at -2.050034 25.07488 90)
			(size 0.519938 1.4986)
			(layers "F.Cu" "F.Mask" "F.Paste")
			(net "GND")
		)
		(pad "100" smd rect
			(at -2.050034 25.925018 90)
			(size 0.519938 1.4986)
			(layers "F.Cu" "F.Mask" "F.Paste")
			(net "M_K_CPU1_SB_DQ<0>")
		)
		(pad "101" smd rect
			(at -2.050034 26.774902 90)
			(size 0.519938 1.4986)
			(layers "F.Cu" "F.Mask" "F.Paste")
			(net "GND")
		)
		(pad "102" smd rect
			(at -2.050034 27.62504 90)
			(size 0.519938 1.4986)
			(layers "F.Cu" "F.Mask" "F.Paste")
			(net "M_K_CPU1_SB_DQ<1>")
		)
		(pad "103" smd rect
			(at -2.050034 28.474924 90)
			(size 0.519938 1.4986)
			(layers "F.Cu" "F.Mask" "F.Paste")
			(net "GND")
		)
		(pad "104" smd rect
			(at -2.050034 29.325062 90)
			(size 0.519938 1.4986)
			(layers "F.Cu" "F.Mask" "F.Paste")
			(net "M_K_CPU1_SB_DQS_DP<0>")
		)
		(pad "105" smd rect
			(at -2.050034 30.174946 90)
			(size 0.519938 1.4986)
			(layers "F.Cu" "F.Mask" "F.Paste")
			(net "M_K_CPU1_SB_DQS_DN<0>")
		)
		(pad "106" smd rect
			(at -2.050034 31.025084 90)
			(size 0.519938 1.4986)
			(layers "F.Cu" "F.Mask" "F.Paste")
			(net "GND")
		)
		(pad "107" smd rect
			(at -2.050034 31.874968 90)
			(size 0.519938 1.4986)
			(layers "F.Cu" "F.Mask" "F.Paste")
			(net "M_K_CPU1_SB_DQ<4>")
		)
		(pad "108" smd rect
			(at -2.050034 32.725106 90)
			(size 0.519938 1.4986)
			(layers "F.Cu" "F.Mask" "F.Paste")
			(net "GND")
		)
		(pad "109" smd rect
			(at -2.050034 33.57499 90)
			(size 0.519938 1.4986)
			(layers "F.Cu" "F.Mask" "F.Paste")
			(net "M_K_CPU1_SB_DQ<5>")
		)
		(pad "110" smd rect
			(at -2.050034 34.425128 90)
			(size 0.519938 1.4986)
			(layers "F.Cu" "F.Mask" "F.Paste")
			(net "GND")
		)
		(pad "111" smd rect
			(at -2.050034 35.275012 90)
			(size 0.519938 1.4986)
			(layers "F.Cu" "F.Mask" "F.Paste")
			(net "M_K_CPU1_SB_DQ<8>")
		)
		(pad "112" smd rect
			(at -2.050034 36.124896 90)
			(size 0.519938 1.4986)
			(layers "F.Cu" "F.Mask" "F.Paste")
			(net "GND")
		)
		(pad "113" smd rect
			(at -2.050034 36.975034 90)
			(size 0.519938 1.4986)
			(layers "F.Cu" "F.Mask" "F.Paste")
			(net "M_K_CPU1_SB_DQ<9>")
		)
		(pad "114" smd rect
			(at -2.050034 37.824918 90)
			(size 0.519938 1.4986)
			(layers "F.Cu" "F.Mask" "F.Paste")
			(net "GND")
		)
		(pad "115" smd rect
			(at -2.050034 38.675056 90)
			(size 0.519938 1.4986)
			(layers "F.Cu" "F.Mask" "F.Paste")
			(net "M_K_CPU1_SB_DQS_DP<1>")
		)
		(pad "116" smd rect
			(at -2.050034 39.52494 90)
			(size 0.519938 1.4986)
			(layers "F.Cu" "F.Mask" "F.Paste")
			(net "M_K_CPU1_SB_DQS_DN<1>")
		)
		(pad "117" smd rect
			(at -2.050034 40.375078 90)
			(size 0.519938 1.4986)
			(layers "F.Cu" "F.Mask" "F.Paste")
			(net "GND")
		)
		(pad "118" smd rect
			(at -2.050034 41.224962 90)
			(size 0.519938 1.4986)
			(layers "F.Cu" "F.Mask" "F.Paste")
			(net "M_K_CPU1_SB_DQ<12>")
		)
		(pad "119" smd rect
			(at -2.050034 42.0751 90)
			(size 0.519938 1.4986)
			(layers "F.Cu" "F.Mask" "F.Paste")
			(net "GND")
		)
		(pad "120" smd rect
			(at -2.050034 42.924984 90)
			(size 0.519938 1.4986)
			(layers "F.Cu" "F.Mask" "F.Paste")
			(net "M_K_CPU1_SB_DQ<13>")
		)
		(pad "121" smd rect
			(at -2.050034 43.775122 90)
			(size 0.519938 1.4986)
			(layers "F.Cu" "F.Mask" "F.Paste")
			(net "GND")
		)
		(pad "122" smd rect
			(at -2.050034 44.625006 90)
			(size 0.519938 1.4986)
			(layers "F.Cu" "F.Mask" "F.Paste")
			(net "M_K_CPU1_SB_DQ<16>")
		)
		(pad "123" smd rect
			(at -2.050034 45.47489 90)
			(size 0.519938 1.4986)
			(layers "F.Cu" "F.Mask" "F.Paste")
			(net "GND")
		)
		(pad "124" smd rect
			(at -2.050034 46.325028 90)
			(size 0.519938 1.4986)
			(layers "F.Cu" "F.Mask" "F.Paste")
			(net "M_K_CPU1_SB_DQ<17>")
		)
		(pad "125" smd rect
			(at -2.050034 47.174912 90)
			(size 0.519938 1.4986)
			(layers "F.Cu" "F.Mask" "F.Paste")
			(net "GND")
		)
		(pad "126" smd rect
			(at -2.050034 48.02505 90)
			(size 0.519938 1.4986)
			(layers "F.Cu" "F.Mask" "F.Paste")
			(net "M_K_CPU1_SB_DQS_DP<2>")
		)
		(pad "127" smd rect
			(at -2.050034 48.874934 90)
			(size 0.519938 1.4986)
			(layers "F.Cu" "F.Mask" "F.Paste")
			(net "M_K_CPU1_SB_DQS_DN<2>")
		)
		(pad "128" smd rect
			(at -2.050034 49.725072 90)
			(size 0.519938 1.4986)
			(layers "F.Cu" "F.Mask" "F.Paste")
			(net "GND")
		)
		(pad "129" smd rect
			(at -2.050034 50.574956 90)
			(size 0.519938 1.4986)
			(layers "F.Cu" "F.Mask" "F.Paste")
			(net "M_K_CPU1_SB_DQ<20>")
		)
		(pad "130" smd rect
			(at -2.050034 51.425094 90)
			(size 0.519938 1.4986)
			(layers "F.Cu" "F.Mask" "F.Paste")
			(net "GND")
		)
		(pad "131" smd rect
			(at -2.050034 52.274978 90)
			(size 0.519938 1.4986)
			(layers "F.Cu" "F.Mask" "F.Paste")
			(net "M_K_CPU1_SB_DQ<21>")
		)
		(pad "132" smd rect
			(at -2.050034 53.125116 90)
			(size 0.519938 1.4986)
			(layers "F.Cu" "F.Mask" "F.Paste")
			(net "GND")
		)
		(pad "133" smd rect
			(at -2.050034 53.975 90)
			(size 0.519938 1.4986)
			(layers "F.Cu" "F.Mask" "F.Paste")
			(net "M_K_CPU1_SB_DQ<24>")
		)
		(pad "134" smd rect
			(at -2.050034 54.824884 90)
			(size 0.519938 1.4986)
			(layers "F.Cu" "F.Mask" "F.Paste")
			(net "GND")
		)
		(pad "135" smd rect
			(at -2.050034 55.675022 90)
			(size 0.519938 1.4986)
			(layers "F.Cu" "F.Mask" "F.Paste")
			(net "M_K_CPU1_SB_DQ<25>")
		)
		(pad "136" smd rect
			(at -2.050034 56.524906 90)
			(size 0.519938 1.4986)
			(layers "F.Cu" "F.Mask" "F.Paste")
			(net "GND")
		)
		(pad "137" smd rect
			(at -2.050034 57.375044 90)
			(size 0.519938 1.4986)
			(layers "F.Cu" "F.Mask" "F.Paste")
			(net "M_K_CPU1_SB_DQS_DP<3>")
		)
		(pad "138" smd rect
			(at -2.050034 58.224928 90)
			(size 0.519938 1.4986)
			(layers "F.Cu" "F.Mask" "F.Paste")
			(net "M_K_CPU1_SB_DQS_DN<3>")
		)
	)
)
